(kicad_pcb
	(version 20260206)
	(generator "pcbnew")
	(generator_version "10.0")
	(general
		(thickness 1.6)
		(legacy_teardrops no)
	)
	(paper "A4")
	(title_block
		(title "panther-plus-userver — 13130-1b_20150205.brd")
		(comment 1 "Honey Badger (Wiwynn) / footprints 154-160 of 1509")
	)
	(layers
		(0 "F.Cu" signal "TOP")
		(4 "In1.Cu" signal "L2")
		(6 "In2.Cu" signal "L3")
		(8 "In3.Cu" signal "L4")
		(10 "In4.Cu" signal "L5")
		(12 "In5.Cu" signal "L6")
		(14 "In6.Cu" signal "L7")
		(16 "In7.Cu" signal "L8")
		(18 "In8.Cu" signal "L9")
		(20 "In9.Cu" signal "L10")
		(22 "In10.Cu" signal "L11")
		(2 "B.Cu" signal "BOTTOM")
		(9 "F.Adhes" user "F.Adhesive")
		(11 "B.Adhes" user "B.Adhesive")
		(13 "F.Paste" user "Package Geometry/Pastemask Top")
		(15 "B.Paste" user "Package Geometry/Pastemask Bottom")
		(5 "F.SilkS" user "Ref Des/Silkscreen Top")
		(7 "B.SilkS" user "Ref Des/Silkscreen Bottom")
		(1 "F.Mask" user "Board Geometry/Soldermask Top")
		(3 "B.Mask" user "Board Geometry/Soldermask Bottom")
		(17 "Dwgs.User" user "User.Drawings")
		(19 "Cmts.User" user "User.Comments")
		(21 "Eco1.User" user "User.Eco1")
		(23 "Eco2.User" user "User.Eco2")
		(25 "Edge.Cuts" user "Board Geometry/Outline")
		(27 "Margin" user)
		(31 "F.CrtYd" user "Package Geometry/Place Bound Top")
		(29 "B.CrtYd" user "Package Geometry/Place Bound Bottom")
		(35 "F.Fab" user "Ref Des/Assembly Top")
		(33 "B.Fab" user "Ref Des/Assembly Bottom")
	)
	(footprint ""
		(layer "F.Cu")
		(at 11.43 -50.4952 90)
		(property "Reference" "C63"
			(at 0 0 90)
			(layer "F.SilkS")
			(hide yes)
			(effects
				(font
					(size 1.27 1.27)
				)
			)
		)
		(property "Value" "SCD1U16V2KX-3GP"
			(at 1.1811 -2.7051 90)
			(unlocked yes)
			(layer "F.Fab")
			(hide yes)
			(effects
				(font
					(size 1.016 1.016)
					(thickness 0.1524)
				)
			)
		)
		(property "Device Type" "C402H22"
			(at 1.1811 -4.2291 90)
			(unlocked yes)
			(layer "F.Fab")
			(hide yes)
			(effects
				(font
					(size 1.016 1.016)
					(thickness 0.1524)
				)
			)
		)
		(duplicate_pad_numbers_are_jumpers no)
		(fp_rect
			(start -0.381 0.7366)
			(end 0.381 -0.7366)
			(stroke
				(width 0)
				(type default)
			)
			(fill no)
			(layer "F.CrtYd")
		)
		(fp_rect
			(start -0.381 0.7366)
			(end 0.381 -0.7366)
			(stroke
				(width 0)
				(type default)
			)
			(fill no)
			(layer "F.Fab")
		)
		(pad "1" smd custom
			(at 0 -0.4572 90)
			(size 0.1143 0.1143)
			(layers "F.Cu" "F.Mask" "F.Paste")
			(net "P2E_CPU_NGFF_TX_DP12")
			(options
				(clearance outline)
				(anchor circle)
			)
			(primitives
				(gr_poly
					(pts
						(arc
							(start -0.254 -0.1778)
							(mid -0.239121 -0.213721)
							(end -0.2032 -0.2286)
						)
						(arc
							(start 0.2032 -0.2286)
							(mid 0.239121 -0.213721)
							(end 0.254 -0.1778)
						)
						(arc
							(start 0.254 0.1778)
							(mid 0.239121 0.213721)
							(end 0.2032 0.2286)
						)
						(arc
							(start -0.2032 0.2286)
							(mid -0.239121 0.213721)
							(end -0.254 0.1778)
						)
					)
					(width 0)
					(fill yes)
				)
			)
		)
		(pad "2" smd custom
			(at 0 0.4572 90)
			(size 0.1143 0.1143)
			(layers "F.Cu" "F.Mask" "F.Paste")
			(net "P2E_CPU_NGFF_C_TX_DP12")
			(options
				(clearance outline)
				(anchor circle)
			)
			(primitives
				(gr_poly
					(pts
						(arc
							(start -0.254 -0.1778)
							(mid -0.239121 -0.213721)
							(end -0.2032 -0.2286)
						)
						(arc
							(start 0.2032 -0.2286)
							(mid 0.239121 -0.213721)
							(end 0.254 -0.1778)
						)
						(arc
							(start 0.254 0.1778)
							(mid 0.239121 0.213721)
							(end 0.2032 0.2286)
						)
						(arc
							(start -0.2032 0.2286)
							(mid -0.239121 0.213721)
							(end -0.254 0.1778)
						)
					)
					(width 0)
					(fill yes)
				)
			)
		)
	)
	(footprint ""
		(layer "F.Cu")
		(at 165.3032 -12.828778 180)
		(property "Reference" "C341"
			(at 0 0 180)
			(layer "F.SilkS")
			(hide yes)
			(effects
				(font
					(size 1.27 1.27)
				)
			)
		)
		(property "Value" "SCD1U16V2KX-3GP"
			(at 1.8923 -1.2065 180)
			(unlocked yes)
			(layer "F.Fab")
			(hide yes)
			(effects
				(font
					(size 1.016 1.016)
					(thickness 0.1524)
				)
			)
		)
		(property "Device Type" "C402H22"
			(at 1.8923 -2.7305 180)
			(unlocked yes)
			(layer "F.Fab")
			(hide yes)
			(effects
				(font
					(size 1.016 1.016)
					(thickness 0.1524)
				)
			)
		)
		(duplicate_pad_numbers_are_jumpers no)
		(fp_rect
			(start -0.381 0.7366)
			(end 0.381 -0.7366)
			(stroke
				(width 0)
				(type default)
			)
			(fill no)
			(layer "F.CrtYd")
		)
		(fp_rect
			(start -0.381 0.7366)
			(end 0.381 -0.7366)
			(stroke
				(width 0)
				(type default)
			)
			(fill no)
			(layer "F.Fab")
		)
		(pad "1" smd custom
			(at 0 -0.4572 180)
			(size 0.1143 0.1143)
			(layers "F.Cu" "F.Mask" "F.Paste")
			(net "PV_VDDR")
			(options
				(clearance outline)
				(anchor circle)
			)
			(primitives
				(gr_poly
					(pts
						(arc
							(start -0.254 -0.1778)
							(mid -0.239121 -0.213721)
							(end -0.2032 -0.2286)
						)
						(arc
							(start 0.2032 -0.2286)
							(mid 0.239121 -0.213721)
							(end 0.254 -0.1778)
						)
						(arc
							(start 0.254 0.1778)
							(mid 0.239121 0.213721)
							(end 0.2032 0.2286)
						)
						(arc
							(start -0.2032 0.2286)
							(mid -0.239121 0.213721)
							(end -0.254 0.1778)
						)
					)
					(width 0)
					(fill yes)
				)
			)
		)
		(pad "2" smd custom
			(at 0 0.4572 180)
			(size 0.1143 0.1143)
			(layers "F.Cu" "F.Mask" "F.Paste")
			(net "GND")
			(options
				(clearance outline)
				(anchor circle)
			)
			(primitives
				(gr_poly
					(pts
						(arc
							(start -0.254 -0.1778)
							(mid -0.239121 -0.213721)
							(end -0.2032 -0.2286)
						)
						(arc
							(start 0.2032 -0.2286)
							(mid 0.239121 -0.213721)
							(end 0.254 -0.1778)
						)
						(arc
							(start 0.254 0.1778)
							(mid 0.239121 0.213721)
							(end 0.2032 0.2286)
						)
						(arc
							(start -0.2032 0.2286)
							(mid -0.239121 0.213721)
							(end -0.254 0.1778)
						)
					)
					(width 0)
					(fill yes)
				)
			)
		)
	)
	(footprint ""
		(layer "F.Cu")
		(at 132.207 -48.514 180)
		(property "Reference" "Q1"
			(at 0 0 180)
			(layer "F.SilkS")
			(hide yes)
			(effects
				(font
					(size 1.27 1.27)
				)
			)
		)
		(property "Value" "MMBT3904TT1G-GP"
			(at -2.032 -3.674618 180)
			(unlocked yes)
			(layer "F.Fab")
			(hide yes)
			(effects
				(font
					(size 1.016 1.016)
					(thickness 0.1524)
				)
			)
		)
		(property "Device Type" "SC75CBE1D6H36"
			(at -2.032 -5.198618 180)
			(unlocked yes)
			(layer "F.Fab")
			(hide yes)
			(effects
				(font
					(size 1.016 1.016)
					(thickness 0.1524)
				)
			)
		)
		(duplicate_pad_numbers_are_jumpers no)
		(fp_poly
			(pts
				(xy 0.381 -1.1938) (xy -0.381 -1.1938) (xy -0.381 -0.6604) (xy -1.0541 -0.6604) (xy -1.0541 0.6604)
				(xy -0.889 0.6604) (xy -0.889 1.1938) (xy 0.889 1.1938) (xy 0.889 0.6604) (xy 1.0541 0.6604) (xy 1.0541 -0.6604)
				(xy 0.381 -0.6604)
			)
			(stroke
				(width 0)
				(type default)
			)
			(fill no)
			(layer "F.CrtYd")
		)
		(fp_poly
			(pts
				(xy 0.381 -1.1938) (xy -0.381 -1.1938) (xy -0.381 -0.6604) (xy -1.0541 -0.6604) (xy -1.0541 0.6604)
				(xy -0.889 0.6604) (xy -0.889 1.1938) (xy 0.889 1.1938) (xy 0.889 0.6604) (xy 1.0541 0.6604) (xy 1.0541 -0.6604)
				(xy 0.381 -0.6604)
			)
			(stroke
				(width 0)
				(type default)
			)
			(fill no)
			(layer "F.Fab")
		)
		(pad "B" smd custom
			(at -0.508 0.6604 180)
			(size 0.127 0.127)
			(layers "F.Cu" "F.Mask" "F.Paste")
			(net "MEMORY_HOT_N_LV_B2")
			(options
				(clearance outline)
				(anchor circle)
			)
			(primitives
				(gr_poly
					(pts
						(arc
							(start -0.0508 0.4064)
							(mid -0.194484 0.346884)
							(end -0.254 0.2032)
						)
						(arc
							(start -0.254 -0.2032)
							(mid -0.194484 -0.346884)
							(end -0.0508 -0.4064)
						)
						(arc
							(start 0.0508 -0.4064)
							(mid 0.194484 -0.346884)
							(end 0.254 -0.2032)
						)
						(arc
							(start 0.254 0.2032)
							(mid 0.194484 0.346884)
							(end 0.0508 0.4064)
						)
					)
					(width 0)
					(fill yes)
				)
			)
		)
		(pad "C" smd custom
			(at 0 -0.6604 180)
			(size 0.127 0.127)
			(layers "F.Cu" "F.Mask" "F.Paste")
			(net "MEMORY_FPGA_HOT#")
			(options
				(clearance outline)
				(anchor circle)
			)
			(primitives
				(gr_poly
					(pts
						(arc
							(start -0.0508 0.4064)
							(mid -0.194484 0.346884)
							(end -0.254 0.2032)
						)
						(arc
							(start -0.254 -0.2032)
							(mid -0.194484 -0.346884)
							(end -0.0508 -0.4064)
						)
						(arc
							(start 0.0508 -0.4064)
							(mid 0.194484 -0.346884)
							(end 0.254 -0.2032)
						)
						(arc
							(start 0.254 0.2032)
							(mid 0.194484 0.346884)
							(end 0.0508 0.4064)
						)
					)
					(width 0)
					(fill yes)
				)
			)
		)
		(pad "E" smd custom
			(at 0.508 0.6604 180)
			(size 0.127 0.127)
			(layers "F.Cu" "F.Mask" "F.Paste")
			(net "MEMORY_HOT_LV_E2#")
			(options
				(clearance outline)
				(anchor circle)
			)
			(primitives
				(gr_poly
					(pts
						(arc
							(start -0.0508 0.4064)
							(mid -0.194484 0.346884)
							(end -0.254 0.2032)
						)
						(arc
							(start -0.254 -0.2032)
							(mid -0.194484 -0.346884)
							(end -0.0508 -0.4064)
						)
						(arc
							(start 0.0508 -0.4064)
							(mid 0.194484 -0.346884)
							(end 0.254 -0.2032)
						)
						(arc
							(start 0.254 0.2032)
							(mid 0.194484 0.346884)
							(end 0.0508 0.4064)
						)
					)
					(width 0)
					(fill yes)
				)
			)
		)
	)
	(footprint ""
		(layer "F.Cu")
		(at 8.509 -61.849 90)
		(property "Reference" "C32"
			(at 0 0 90)
			(layer "F.SilkS")
			(hide yes)
			(effects
				(font
					(size 1.27 1.27)
				)
			)
		)
		(property "Value" "SCD1U16V2KX-3GP"
			(at 1.1811 -2.7051 90)
			(unlocked yes)
			(layer "F.Fab")
			(hide yes)
			(effects
				(font
					(size 1.016 1.016)
					(thickness 0.1524)
				)
			)
		)
		(property "Device Type" "C402H22"
			(at 1.1811 -4.2291 90)
			(unlocked yes)
			(layer "F.Fab")
			(hide yes)
			(effects
				(font
					(size 1.016 1.016)
					(thickness 0.1524)
				)
			)
		)
		(duplicate_pad_numbers_are_jumpers no)
		(fp_rect
			(start -0.381 0.7366)
			(end 0.381 -0.7366)
			(stroke
				(width 0)
				(type default)
			)
			(fill no)
			(layer "F.CrtYd")
		)
		(fp_rect
			(start -0.381 0.7366)
			(end 0.381 -0.7366)
			(stroke
				(width 0)
				(type default)
			)
			(fill no)
			(layer "F.Fab")
		)
		(pad "1" smd custom
			(at 0 -0.4572 90)
			(size 0.1143 0.1143)
			(layers "F.Cu" "F.Mask" "F.Paste")
			(net "P2E_CPU_NGFF_C_RX_DN14")
			(options
				(clearance outline)
				(anchor circle)
			)
			(primitives
				(gr_poly
					(pts
						(arc
							(start -0.254 -0.1778)
							(mid -0.239121 -0.213721)
							(end -0.2032 -0.2286)
						)
						(arc
							(start 0.2032 -0.2286)
							(mid 0.239121 -0.213721)
							(end 0.254 -0.1778)
						)
						(arc
							(start 0.254 0.1778)
							(mid 0.239121 0.213721)
							(end 0.2032 0.2286)
						)
						(arc
							(start -0.2032 0.2286)
							(mid -0.239121 0.213721)
							(end -0.254 0.1778)
						)
					)
					(width 0)
					(fill yes)
				)
			)
		)
		(pad "2" smd custom
			(at 0 0.4572 90)
			(size 0.1143 0.1143)
			(layers "F.Cu" "F.Mask" "F.Paste")
			(net "P2E_CPU_NGFF_RX_DN14")
			(options
				(clearance outline)
				(anchor circle)
			)
			(primitives
				(gr_poly
					(pts
						(arc
							(start -0.254 -0.1778)
							(mid -0.239121 -0.213721)
							(end -0.2032 -0.2286)
						)
						(arc
							(start 0.2032 -0.2286)
							(mid 0.239121 -0.213721)
							(end 0.254 -0.1778)
						)
						(arc
							(start 0.254 0.1778)
							(mid 0.239121 0.213721)
							(end 0.2032 0.2286)
						)
						(arc
							(start -0.2032 0.2286)
							(mid -0.239121 0.213721)
							(end -0.254 0.1778)
						)
					)
					(width 0)
					(fill yes)
				)
			)
		)
	)
	(footprint ""
		(layer "F.Cu")
		(at 34.29 -13.081)
		(property "Reference" "R463"
			(at 0 0 0)
			(layer "F.SilkS")
			(hide yes)
			(effects
				(font
					(size 1.27 1.27)
				)
			)
		)
		(property "Value" "4K7R2F-GP"
			(at 1.7907 -1.1176 0)
			(unlocked yes)
			(layer "F.Fab")
			(hide yes)
			(effects
				(font
					(size 1.016 1.016)
					(thickness 0.1524)
				)
			)
		)
		(property "Device Type" "R402H16"
			(at 1.7907 -2.6416 0)
			(unlocked yes)
			(layer "F.Fab")
			(hide yes)
			(effects
				(font
					(size 1.016 1.016)
					(thickness 0.1524)
				)
			)
		)
		(duplicate_pad_numbers_are_jumpers no)
		(fp_rect
			(start -0.381 0.8382)
			(end 0.381 -0.8382)
			(stroke
				(width 0)
				(type default)
			)
			(fill no)
			(layer "F.CrtYd")
		)
		(fp_rect
			(start -0.381 0.8382)
			(end 0.381 -0.8382)
			(stroke
				(width 0)
				(type default)
			)
			(fill no)
			(layer "F.Fab")
		)
		(pad "1" smd custom
			(at 0 -0.4318)
			(size 0.127 0.127)
			(layers "F.Cu" "F.Mask" "F.Paste")
			(net "P3V3_STBY")
			(options
				(clearance outline)
				(anchor circle)
			)
			(primitives
				(gr_poly
					(pts
						(arc
							(start -0.2032 -0.2794)
							(mid -0.239121 -0.264521)
							(end -0.254 -0.2286)
						)
						(arc
							(start -0.254 0.2286)
							(mid -0.239121 0.264521)
							(end -0.2032 0.2794)
						)
						(arc
							(start 0.2032 0.2794)
							(mid 0.239121 0.264521)
							(end 0.254 0.2286)
						)
						(arc
							(start 0.254 -0.2286)
							(mid 0.239121 -0.264521)
							(end 0.2032 -0.2794)
						)
					)
					(width 0)
					(fill yes)
				)
			)
		)
		(pad "2" smd custom
			(at 0 0.4318)
			(size 0.127 0.127)
			(layers "F.Cu" "F.Mask" "F.Paste")
			(net "PCIE_GF_I2C_DATA")
			(options
				(clearance outline)
				(anchor circle)
			)
			(primitives
				(gr_poly
					(pts
						(arc
							(start -0.2032 -0.2794)
							(mid -0.239121 -0.264521)
							(end -0.254 -0.2286)
						)
						(arc
							(start -0.254 0.2286)
							(mid -0.239121 0.264521)
							(end -0.2032 0.2794)
						)
						(arc
							(start 0.2032 0.2794)
							(mid 0.239121 0.264521)
							(end 0.254 0.2286)
						)
						(arc
							(start 0.254 -0.2286)
							(mid 0.239121 -0.264521)
							(end 0.2032 -0.2794)
						)
					)
					(width 0)
					(fill yes)
				)
			)
		)
	)
	(footprint ""
		(layer "F.Cu")
		(at 200.787 -61.722 90)
		(property "Reference" "PTC3"
			(at 0 0 90)
			(layer "F.SilkS")
			(hide yes)
			(effects
				(font
					(size 1.27 1.27)
				)
			)
		)
		(property "Value" "SE470UF2VDM-GP"
			(at -3.220466 1.242822 90)
			(unlocked yes)
			(layer "F.Fab")
			(hide yes)
			(effects
				(font
					(size 1.016 1.016)
					(thickness 0.1524)
				)
			)
		)
		(property "Device Type" "CT7343H83"
			(at -3.220466 -0.281178 90)
			(unlocked yes)
			(layer "F.Fab")
			(hide yes)
			(effects
				(font
					(size 1.016 1.016)
					(thickness 0.1524)
				)
			)
		)
		(duplicate_pad_numbers_are_jumpers no)
		(fp_line
			(start -2.206752 -4.2926)
			(end 2.155698 -4.2926)
			(stroke
				(width 0.508)
				(type default)
			)
			(layer "F.SilkS")
		)
		(fp_rect
			(start -2.1463 3.6449)
			(end 2.1463 -3.6449)
			(stroke
				(width 0)
				(type default)
			)
			(fill no)
			(layer "F.CrtYd")
		)
		(fp_poly
			(pts
				(xy -3.81 3.9116) (xy -3.81 -3.9116) (xy -2.54 -3.9116) (xy -2.4003 -3.9116) (xy -2.4003 -4.0386)
				(xy 2.4003 -4.0386) (xy 2.4003 -3.9116) (xy 2.54 -3.9116) (xy 2.5654 -3.9116) (xy 3.81 -3.9116)
				(xy 3.81 -1.6256) (xy 2.1463 -1.6256) (xy 2.1463 -3.6449) (xy -2.1463 -3.6449) (xy -2.1463 3.6449)
				(xy 2.1463 3.6449) (xy 2.1463 -1.6129) (xy 3.81 -1.6129) (xy 3.81 3.9116) (xy 2.4003 3.9116) (xy 2.4003 3.9243)
				(xy 2.4003 4.0386) (xy -2.4003 4.0386) (xy -2.4003 3.9116)
			)
			(stroke
				(width 0)
				(type default)
			)
			(fill no)
			(layer "F.CrtYd")
		)
		(fp_rect
			(start 2.4003 3.9116)
			(end 3.81 -3.9116)
			(stroke
				(width 0)
				(type default)
			)
			(fill no)
			(layer "F.Fab")
		)
		(fp_rect
			(start -3.81 3.9116)
			(end -2.4003 -3.9116)
			(stroke
				(width 0)
				(type default)
			)
			(fill no)
			(layer "F.Fab")
		)
		(fp_rect
			(start -2.4003 4.0386)
			(end 2.4003 -4.0386)
			(stroke
				(width 0)
				(type default)
			)
			(fill no)
			(layer "F.Fab")
		)
		(pad "1" smd rect
			(at 0 -2.9591 90)
			(size 2.413 1.905)
			(layers "F.Cu" "F.Mask" "F.Paste")
			(net "PV_VDDR")
		)
		(pad "2" smd rect
			(at 0 2.9591 90)
			(size 2.413 1.905)
			(layers "F.Cu" "F.Mask" "F.Paste")
			(net "GND")
		)
	)
	(footprint ""
		(layer "F.Cu")
		(at 69.088 -45.3136 90)
		(property "Reference" "R61"
			(at 0 0 90)
			(layer "F.SilkS")
			(hide yes)
			(effects
				(font
					(size 1.27 1.27)
				)
			)
		)
		(property "Value" "0R2J-2-GP"
			(at 0.064008 -3.993896 90)
			(unlocked yes)
			(layer "F.Fab")
			(hide yes)
			(effects
				(font
					(size 1.016 1.016)
					(thickness 0.1524)
				)
			)
		)
		(property "Device Type" "R402H16"
			(at 0.064008 -5.517896 90)
			(unlocked yes)
			(layer "F.Fab")
			(hide yes)
			(effects
				(font
					(size 1.016 1.016)
					(thickness 0.1524)
				)
			)
		)
		(duplicate_pad_numbers_are_jumpers no)
		(fp_rect
			(start -0.381 0.8382)
			(end 0.381 -0.8382)
			(stroke
				(width 0)
				(type default)
			)
			(fill no)
			(layer "F.CrtYd")
		)
		(fp_rect
			(start -0.381 0.8382)
			(end 0.381 -0.8382)
			(stroke
				(width 0)
				(type default)
			)
			(fill no)
			(layer "F.Fab")
		)
		(pad "1" smd custom
			(at 0 -0.4318 90)
			(size 0.127 0.127)
			(layers "F.Cu" "F.Mask" "F.Paste")
			(net "SMBUS_PECI_R_CLK")
			(options
				(clearance outline)
				(anchor circle)
			)
			(primitives
				(gr_poly
					(pts
						(arc
							(start -0.2032 -0.2794)
							(mid -0.239121 -0.264521)
							(end -0.254 -0.2286)
						)
						(arc
							(start -0.254 0.2286)
							(mid -0.239121 0.264521)
							(end -0.2032 0.2794)
						)
						(arc
							(start 0.2032 0.2794)
							(mid 0.239121 0.264521)
							(end 0.254 0.2286)
						)
						(arc
							(start 0.254 -0.2286)
							(mid 0.239121 -0.264521)
							(end 0.2032 -0.2794)
						)
					)
					(width 0)
					(fill yes)
				)
			)
		)
		(pad "2" smd custom
			(at 0 0.4318 90)
			(size 0.127 0.127)
			(layers "F.Cu" "F.Mask" "F.Paste")
			(net "SMBUS_PECI_CLK")
			(options
				(clearance outline)
				(anchor circle)
			)
			(primitives
				(gr_poly
					(pts
						(arc
							(start -0.2032 -0.2794)
							(mid -0.239121 -0.264521)
							(end -0.254 -0.2286)
						)
						(arc
							(start -0.254 0.2286)
							(mid -0.239121 0.264521)
							(end -0.2032 0.2794)
						)
						(arc
							(start 0.2032 0.2794)
							(mid 0.239121 0.264521)
							(end 0.254 0.2286)
						)
						(arc
							(start 0.254 -0.2286)
							(mid 0.239121 -0.264521)
							(end 0.2032 -0.2794)
						)
					)
					(width 0)
					(fill yes)
				)
			)
		)
	)
)
